# S9S_MB_2U (Grand Teton) — schematic netlist excerpt (pin names and nets, part order shuffled) for the footprints in the layout excerpt that follows; sources: Cadence DE-HDL packaged netlist, KiCad conversion of 03242023_DA0F0TMBIJ0_F0T_Motherboard_J_brd_V01_OCP.brd

PC500_P1_7  Q_CAP  22UF 4V 20% X6S  pkg C0805  page 288 : A = PVCCIN_CPU1 ; B = GND
C1214  Q_CAP  2.2UF 10V 10% X6S  pkg C0402  page 189 : A = P1V05_PCH_AUX ; B = GND
R32  Q_RES  127K 1% CHIP  pkg 0402LF  page 88 : A = PD_CHD_CPU0_DIMM1_SAA ; B = GND

(kicad_pcb
	(version 20260206)
	(generator "pcbnew")
	(generator_version "10.0")
	(general
		(thickness 1.6)
		(legacy_teardrops no)
	)
	(paper "A4")
	(title_block
		(title "03242023_DA0F0TMBIJ0_F0T_Motherboard_J_brd_V01_OCP.brd")
		(comment 1 "Grand Teton / footprints 5142-5144 of 6105")
	)
	(layers
		(0 "F.Cu" signal "TOP")
		(4 "In1.Cu" signal "GND")
		(6 "In2.Cu" signal "IN1")
		(8 "In3.Cu" signal "GND1")
		(10 "In4.Cu" signal "IN2")
		(12 "In5.Cu" signal "GND2")
		(14 "In6.Cu" signal "IN3")
		(16 "In7.Cu" signal "GND3")
		(18 "In8.Cu" signal "VCC")
		(20 "In9.Cu" signal "VCC1")
		(22 "In10.Cu" signal "GND4")
		(24 "In11.Cu" signal "IN4")
		(26 "In12.Cu" signal "GND5")
		(28 "In13.Cu" signal "IN5")
		(30 "In14.Cu" signal "GND6")
		(32 "In15.Cu" signal "IN6")
		(34 "In16.Cu" signal "GND7")
		(2 "B.Cu" signal "BOTTOM")
		(9 "F.Adhes" user "F.Adhesive")
		(11 "B.Adhes" user "B.Adhesive")
		(13 "F.Paste" user "Package Geometry/Pastemask Top")
		(15 "B.Paste" user "Package Geometry/Pastemask Bottom")
		(5 "F.SilkS" user "Ref Des/Silkscreen Top")
		(7 "B.SilkS" user "Ref Des/Silkscreen Bottom")
		(1 "F.Mask" user "Board Geometry/Soldermask Top")
		(3 "B.Mask" user "Board Geometry/Soldermask Bottom")
		(17 "Dwgs.User" user "User.Drawings")
		(19 "Cmts.User" user "User.Comments")
		(21 "Eco1.User" user "User.Eco1")
		(23 "Eco2.User" user "User.Eco2")
		(25 "Edge.Cuts" user "Board Geometry/Outline")
		(27 "Margin" user)
		(31 "F.CrtYd" user "Package Geometry/Place Bound Top")
		(29 "B.CrtYd" user "Package Geometry/Place Bound Bottom")
		(35 "F.Fab" user "Ref Des/Assembly Top")
		(33 "B.Fab" user "Ref Des/Assembly Bottom")
	)
	(footprint ""
		(layer "B.Cu")
		(at 335.909158 -45.129704 90)
		(property "Reference" "C1214"
			(at 0 0 90)
			(layer "B.SilkS")
			(hide yes)
			(effects
				(font
					(size 1.27 1.27)
				)
				(justify mirror)
			)
		)
		(property "Value" ""
			(at 0 0 90)
			(layer "B.Fab")
			(effects
				(font
					(size 1.27 1.27)
				)
				(justify mirror)
			)
		)
		(duplicate_pad_numbers_are_jumpers no)
		(fp_line
			(start 0.7874 -0.4064)
			(end -0.7874 -0.4064)
			(stroke
				(width 0.1524)
				(type default)
			)
			(layer "B.SilkS")
		)
		(fp_line
			(start -0.7874 -0.4064)
			(end -0.7874 0.4064)
			(stroke
				(width 0.1524)
				(type default)
			)
			(layer "B.SilkS")
		)
		(fp_line
			(start 0.7874 0.4064)
			(end 0.7874 -0.4064)
			(stroke
				(width 0.1524)
				(type default)
			)
			(layer "B.SilkS")
		)
		(fp_line
			(start -0.7874 0.4064)
			(end 0.7874 0.4064)
			(stroke
				(width 0.1524)
				(type default)
			)
			(layer "B.SilkS")
		)
		(fp_line
			(start 0.67945 -0.305054)
			(end 0.12065 -0.305054)
			(stroke
				(width 0.1)
				(type default)
			)
			(layer "B.Fab")
		)
		(fp_line
			(start 0.12065 -0.305054)
			(end 0.12065 -0.2794)
			(stroke
				(width 0.1)
				(type default)
			)
			(layer "B.Fab")
		)
		(fp_line
			(start -0.12065 -0.3048)
			(end -0.67945 -0.3048)
			(stroke
				(width 0.1)
				(type default)
			)
			(layer "B.Fab")
		)
		(fp_line
			(start -0.67945 -0.3048)
			(end -0.67945 0.3048)
			(stroke
				(width 0.1)
				(type default)
			)
			(layer "B.Fab")
		)
		(fp_line
			(start 0.12065 -0.2794)
			(end -0.12065 -0.2794)
			(stroke
				(width 0.1)
				(type default)
			)
			(layer "B.Fab")
		)
		(fp_line
			(start -0.12065 -0.2794)
			(end -0.12065 -0.3048)
			(stroke
				(width 0.1)
				(type default)
			)
			(layer "B.Fab")
		)
		(fp_line
			(start 0.12065 0.2794)
			(end 0.12065 0.3048)
			(stroke
				(width 0.1)
				(type default)
			)
			(layer "B.Fab")
		)
		(fp_line
			(start -0.120396 0.2794)
			(end 0.12065 0.2794)
			(stroke
				(width 0.1)
				(type default)
			)
			(layer "B.Fab")
		)
		(fp_line
			(start 0.67945 0.3048)
			(end 0.67945 -0.305054)
			(stroke
				(width 0.1)
				(type default)
			)
			(layer "B.Fab")
		)
		(fp_line
			(start 0.12065 0.3048)
			(end 0.67945 0.3048)
			(stroke
				(width 0.1)
				(type default)
			)
			(layer "B.Fab")
		)
		(fp_line
			(start -0.120396 0.3048)
			(end -0.120396 0.2794)
			(stroke
				(width 0.1)
				(type default)
			)
			(layer "B.Fab")
		)
		(fp_line
			(start -0.67945 0.3048)
			(end -0.120396 0.3048)
			(stroke
				(width 0.1)
				(type default)
			)
			(layer "B.Fab")
		)
		(pad "1" smd circle
			(at 0.40005 0 270)
			(size 0 0)
			(layers "B.Cu" "B.Mask" "B.Paste")
			(net "P1V05_PCH_AUX")
		)
		(pad "2" smd circle
			(at -0.40005 0 270)
			(size 0 0)
			(layers "B.Cu" "B.Mask" "B.Paste")
			(net "GND")
		)
	)
	(footprint ""
		(layer "B.Cu")
		(at 81.681574 -331.58938 -90)
		(property "Reference" "PC500_P1_7"
			(at 0 0 90)
			(layer "B.SilkS")
			(hide yes)
			(effects
				(font
					(size 1.27 1.27)
				)
				(justify mirror)
			)
		)
		(property "Value" ""
			(at 0 0 90)
			(layer "B.Fab")
			(effects
				(font
					(size 1.27 1.27)
				)
				(justify mirror)
			)
		)
		(duplicate_pad_numbers_are_jumpers no)
		(fp_line
			(start -1.524 0.762)
			(end 1.524 0.762)
			(stroke
				(width 0.1524)
				(type default)
			)
			(layer "B.SilkS")
		)
		(fp_line
			(start 1.524 0.762)
			(end 1.524 -0.762)
			(stroke
				(width 0.1524)
				(type default)
			)
			(layer "B.SilkS")
		)
		(fp_line
			(start -1.524 -0.762)
			(end -1.524 0.762)
			(stroke
				(width 0.1524)
				(type default)
			)
			(layer "B.SilkS")
		)
		(fp_line
			(start 1.524 -0.762)
			(end -1.524 -0.762)
			(stroke
				(width 0.1524)
				(type default)
			)
			(layer "B.SilkS")
		)
		(fp_line
			(start -1.1049 0.724916)
			(end -1.1049 -0.724916)
			(stroke
				(width 0.1)
				(type default)
			)
			(layer "B.Fab")
		)
		(fp_line
			(start 1.1049 0.724916)
			(end -1.1049 0.724916)
			(stroke
				(width 0.1)
				(type default)
			)
			(layer "B.Fab")
		)
		(fp_line
			(start -1.1049 -0.724916)
			(end 1.1049 -0.724916)
			(stroke
				(width 0.1)
				(type default)
			)
			(layer "B.Fab")
		)
		(fp_line
			(start 1.1049 -0.724916)
			(end 1.1049 0.724916)
			(stroke
				(width 0.1)
				(type default)
			)
			(layer "B.Fab")
		)
		(pad "1" smd rect
			(at 0.889 0 270)
			(size 1.016 1.27)
			(layers "B.Cu" "B.Mask" "B.Paste")
			(net "PVCCIN_CPU1")
		)
		(pad "2" smd rect
			(at -0.889 0 270)
			(size 1.016 1.27)
			(layers "B.Cu" "B.Mask" "B.Paste")
			(net "GND")
		)
	)
	(footprint ""
		(layer "B.Cu")
		(at 257.91287 -318.582802)
		(property "Reference" "R32"
			(at 0 0 0)
			(layer "B.SilkS")
			(hide yes)
			(effects
				(font
					(size 1.27 1.27)
				)
				(justify mirror)
			)
		)
		(property "Value" ""
			(at 0 0 0)
			(layer "B.Fab")
			(effects
				(font
					(size 1.27 1.27)
				)
				(justify mirror)
			)
		)
		(duplicate_pad_numbers_are_jumpers no)
		(fp_line
			(start -0.7874 -0.4064)
			(end -0.7874 0.4064)
			(stroke
				(width 0.1524)
				(type default)
			)
			(layer "B.SilkS")
		)
		(fp_line
			(start -0.7874 0.4064)
			(end 0.7874 0.4064)
			(stroke
				(width 0.1524)
				(type default)
			)
			(layer "B.SilkS")
		)
		(fp_line
			(start 0.7874 -0.4064)
			(end -0.7874 -0.4064)
			(stroke
				(width 0.1524)
				(type default)
			)
			(layer "B.SilkS")
		)
		(fp_line
			(start 0.7874 0.4064)
			(end 0.7874 -0.4064)
			(stroke
				(width 0.1524)
				(type default)
			)
			(layer "B.SilkS")
		)
		(fp_line
			(start -0.67945 -0.3048)
			(end -0.67945 0.3048)
			(stroke
				(width 0.1)
				(type default)
			)
			(layer "B.Fab")
		)
		(fp_line
			(start -0.67945 0.3048)
			(end -0.120396 0.3048)
			(stroke
				(width 0.1)
				(type default)
			)
			(layer "B.Fab")
		)
		(fp_line
			(start -0.12065 -0.3048)
			(end -0.67945 -0.3048)
			(stroke
				(width 0.1)
				(type default)
			)
			(layer "B.Fab")
		)
		(fp_line
			(start -0.12065 -0.2794)
			(end -0.12065 -0.3048)
			(stroke
				(width 0.1)
				(type default)
			)
			(layer "B.Fab")
		)
		(fp_line
			(start -0.120396 0.2794)
			(end 0.12065 0.2794)
			(stroke
				(width 0.1)
				(type default)
			)
			(layer "B.Fab")
		)
		(fp_line
			(start -0.120396 0.3048)
			(end -0.120396 0.2794)
			(stroke
				(width 0.1)
				(type default)
			)
			(layer "B.Fab")
		)
		(fp_line
			(start 0.12065 -0.305054)
			(end 0.12065 -0.2794)
			(stroke
				(width 0.1)
				(type default)
			)
			(layer "B.Fab")
		)
		(fp_line
			(start 0.12065 -0.2794)
			(end -0.12065 -0.2794)
			(stroke
				(width 0.1)
				(type default)
			)
			(layer "B.Fab")
		)
		(fp_line
			(start 0.12065 0.2794)
			(end 0.12065 0.3048)
			(stroke
				(width 0.1)
				(type default)
			)
			(layer "B.Fab")
		)
		(fp_line
			(start 0.12065 0.3048)
			(end 0.67945 0.3048)
			(stroke
				(width 0.1)
				(type default)
			)
			(layer "B.Fab")
		)
		(fp_line
			(start 0.67945 -0.305054)
			(end 0.12065 -0.305054)
			(stroke
				(width 0.1)
				(type default)
			)
			(layer "B.Fab")
		)
		(fp_line
			(start 0.67945 0.3048)
			(end 0.67945 -0.305054)
			(stroke
				(width 0.1)
				(type default)
			)
			(layer "B.Fab")
		)
		(pad "1" smd circle
			(at 0.40005 0 180)
			(size 0 0)
			(layers "B.Cu" "B.Mask" "B.Paste")
			(net "PD_CHD_CPU0_DIMM1_SAA")
		)
		(pad "2" smd circle
			(at -0.40005 0 180)
			(size 0 0)
			(layers "B.Cu" "B.Mask" "B.Paste")
			(net "GND")
		)
	)
)
